5
5
4
4
3
3
2
2
1
1
D D
C C
B B
A A
POWER TRANSITION BOARD 
Pulling Out 
Detection 
LED TX: LED16 
LED RX:Q31 
Board To Wire Connection 
4P20 CONN 
4x PWR/GND Pins 
20x Signals Pins 
36P24 Golden Finger 
36x PWR/GND Pins 
24x Signals Pins 
Slide Switch: SW1 
Green LED: LED1 
FCB 
Reserved I2C Buffer 
PCA9511 Board To Board Connection 
DPB 
Title 
Size Document Number R e v 
Date: Sheet 
o f 
HONEY BADGER_PTB
-1
BLOCK DIAGRAM
A3
1 5Tuesday, January 20, 2015
Wiwynn
H/W R&D Dept. II
8F,90,Sec. 1,Hsin Tai Wu Rd,
Hsichih, Taipei Hsien 221, Taiwan, R.O.C
Title 
Size Document Number R e v 
Date: Sheet 
o f 
HONEY BADGER_PTB
-1
BLOCK DIAGRAM
A3
1 5Tuesday, January 20, 2015
Wiwynn
H/W R&D Dept. II
8F,90,Sec. 1,Hsin Tai Wu Rd,
Hsichih, Taipei Hsien 221, Taiwan, R.O.C
Title 
Size Document Number R e v 
Date: Sheet 
o f 
HONEY BADGER_PTB
-1
BLOCK DIAGRAM
A3
1 5Tuesday, January 20, 2015
Wiwynn
H/W R&D Dept. II
8F,90,Sec. 1,Hsin Tai Wu Rd,
Hsichih, Taipei Hsien 221, Taiwan, R.O.C



5
5
4
4
3
3
2
2
1
1
D D
C C
B B
A A
PIN Definition DY=Dummy parts 
  =not populated 
SCD1U10V2KX-5GP 
D1U = 0.1uF (2D2U means 2.2uF) 
10Voltage (6D3V means 6.3V) 
2 = size 0402, K tolerance 
K=tolerance 
[C code as below:] 
G=2% 
J=5% 
K=10% 
M=20% 
X=temp characteristics 
[C Series/Temp] 
N=NPO 
X=X7R/X5R 
Y=Y5V 
-5=different symbol/customer 
GP= Green Part (RoHS) 
562R2F- GP 
562 = 562 ohm, (2K2R means 2.2K ohm) 
2 = size 0402 
F = 1% tolerance 
GP= Green Part (RoHS) 
RC size code as below: 
1 = 0201 
2= 0402 
3= 0603 
5= 0805 
6= 1206 
R tolerance code as below: 
D=0.5% 
F= 1% 
J= 5% 
Golden Finger 
To DPB 
4P20S 
To FCB 
Title 
Size Document Number R e v 
Date: Sheet 
o f 
HONEY BADGER_PTB
-1
PIN Definition
A3
2 5Tuesday, January 20, 2015
Wiwynn
H/W R&D Dept. II
8F,90,Sec. 1,Hsin Tai Wu Rd,
Hsichih, Taipei Hsien 221, Taiwan, R.O.C
Title 
Size Document Number R e v 
Date: Sheet 
o f 
HONEY BADGER_PTB
-1
PIN Definition
A3
2 5Tuesday, January 20, 2015
Wiwynn
H/W R&D Dept. II
8F,90,Sec. 1,Hsin Tai Wu Rd,
Hsichih, Taipei Hsien 221, Taiwan, R.O.C
Title 
Size Document Number R e v 
Date: Sheet 
o f 
HONEY BADGER_PTB
-1
PIN Definition
A3
2 5Tuesday, January 20, 2015
Wiwynn
H/W R&D Dept. II
8F,90,Sec. 1,Hsin Tai Wu Rd,
Hsichih, Taipei Hsien 221, Taiwan, R.O.C



5
5
4
4
3
3
2
2
1
1
D D
C C
B B
A A
I2C_C_BUFFER 
PULLING OUT DETECTION 
EMITTER DETECTOR 
"H"=Tray is "pulling out" 
"L"=Tray is "inside the chassis" 
FCB 
DPB DPB 
FCB 
I2C_C_BUF_SDAOUT
I2C_C_BUF_EN
I2C_C_BUF_SCLOUT
EMITTER_K 
IR_switch_E 
TRAY_PRESENT_OUT_NET_B
Tray present_OUT#_C
I2C_C_BUF_SCLIN
TRAY PRESENT_OUT_NET
TRAY_MOSFET_G
DETECTOR_C
I2C_C_BUF_SDAIN
I2C_C_BUF_READY
P3V3
P3V3
P3V3
P3V3
P3V3
P3V3
P3V3 P5VA
P3V3
P3V3
P3V3
SELF_TRAY_PRESENT 4
I2C_C_SCL4
I2C_C_BUF_SCL4
I2C_C_SDA 4
I2C_C_BUF_SDA 4
Title 
Size Document Number R e v 
Date: Sheet 
o f 
HONEY BADGER_PTB
-1
I2C_C BUFFER&PULLING OUT
A3
3 5Tuesday, January 20, 2015
Wiwynn
H/W R&D Dept. II
8F,90,Sec. 1,Hsin Tai Wu Rd,
Hsichih, Taipei Hsien 221, Taiwan, R.O.C
Title 
Size Document Number R e v 
Date: Sheet 
o f 
HONEY BADGER_PTB
-1
I2C_C BUFFER&PULLING OUT
A3
3 5Tuesday, January 20, 2015
Wiwynn
H/W R&D Dept. II
8F,90,Sec. 1,Hsin Tai Wu Rd,
Hsichih, Taipei Hsien 221, Taiwan, R.O.C
Title 
Size Document Number R e v 
Date: Sheet 
o f 
HONEY BADGER_PTB
-1
I2C_C BUFFER&PULLING OUT
A3
3 5Tuesday, January 20, 2015
Wiwynn
H/W R&D Dept. II
8F,90,Sec. 1,Hsin Tai Wu Rd,
Hsichih, Taipei Hsien 221, Taiwan, R.O.C
R486
0R2J-2-GP
NOPOP
1 2
R379
10KR2F-2-GP
1 2
C344 
SCD1U50V3KX-GP 
1 2
Q31
SENSOR-2P-GP-U
EC
R480
0R2J-2-GP
1 2
R342
10KR2F-2-GP
1 2
R485
0R2J-2-GP
NOPOP
1 2
R484
0R2J-2-GP
NOPOP
1 2
R369
4K7R2J-2-GP
NOPOP
1 2
PR65
0R3J-0-U-GP
1 2
LED16
LED-IR-1-GP
A K
R374
470KR2F-GP
1 2
R376
100KR2F-L1-GP
1 2
U51
PCA9511ADP-T-GP
ENABLE1
SCLOUT2
SCLIN3
GND4 READY 5SDAIN 6SDAOUT 7VCC 8
R366
0R2J-2-GP
1 2
R365
0R2J-2-GP
NOPOP
1 2
R370
4K7R2J-2-GP
NOPOP
1 2
R378
68R5J-GP
1 2
Q34
2N7002-11-GP
G
SD
R353
10KR2F-2-GP
1 2
Q33
MMBT2222A-3-GP
C
B
E
PR64
0R3J-0-U-GP
NOPOP
1 2
R375
100R2F-L1-GP-U
1 2
R487
0R2J-2-GP
NOPOP
1 2
R481
0R2J-2-GP
1 2
R344
10KR2F-2-GP
1 2
C345
SCD01U50V2KX-1GP
1 2
TP9
TPAD32-GP
1
R482
0R2J-2-GP
1 2
R343
10KR2F-2-GP
1 2



5
5
4
4
3
3
2
2
1
1
D D
C C
B B
A A
4P20S PWR CONN 
SCREW HOLDs 
GOLDEN_FINGER 
PWM_EXP_B_OUTPWM_EXP_B
SELF_1B&2B_HB
PEER_TRAY_PRESENT
TRAY_ID
TRAY_ID
SD_LATCH_RELEASE
PEER_1A&2A_HB
FCB_HW_REV
SELF_1A&2A_HB
SELF_1B&2B_HB
PWM_EXP_B
STRADDLE_I2C_C_SDA
PWM_EXP_A
TPS2490_LED 
PEER_1B&2B_HB
SD_LATCH_RELEASE
PEER_1A&2A_HB
FCB_HW_REV
PEER_TRAY_PRESENTPEER_1B&2B_HB
PWM_EXP_A
SELF_1A&2A_HB
STRADDLE_I2C_C_SCL
I2C_C_BUF_SDA_CONN
PWM_EXP_A_OUT
I2C_C_BUF_SDA_CONN
I2C_C_BUF_SCL_CONN
TPS2490_DISABLE 
I2C_C_BUF_SCL_CONN TPS2490_EN2
TPS2490_EN1
P12V
P12V
P12V
P3V3
P12V
P5VA
P12V
I2C_C_BUF_SCL3
SELF_TRAY_PRESENT 3
SELF_TRAY_PRESENT 3
I2C_C_SCL 3
I2C_C_SDA 3
I2C_C_BUF_SDA3
Title 
Size Document Number R e v 
Date: Sheet 
o f 
HONEY BADGER_PTB
-1
CONNs
A3
4 5Tuesday, January 20, 2015
Wiwynn
H/W R&D Dept. II
8F,90,Sec. 1,Hsin Tai Wu Rd,
Hsichih, Taipei Hsien 221, Taiwan, R.O.C
Title 
Size Document Number R e v 
Date: Sheet 
o f 
HONEY BADGER_PTB
-1
CONNs
A3
4 5Tuesday, January 20, 2015
Wiwynn
H/W R&D Dept. II
8F,90,Sec. 1,Hsin Tai Wu Rd,
Hsichih, Taipei Hsien 221, Taiwan, R.O.C
Title 
Size Document Number R e v 
Date: Sheet 
o f 
HONEY BADGER_PTB
-1
CONNs
A3
4 5Tuesday, January 20, 2015
Wiwynn
H/W R&D Dept. II
8F,90,Sec. 1,Hsin Tai Wu Rd,
Hsichih, Taipei Hsien 221, Taiwan, R.O.C
LED1
LED-G-203-GP
A K
R389 0R2J-2-GP1 2
TC5 
ST68U16VDM-1-GP 
1 2
C348
SC10U25V5KX-GP
1 2
C363
SC47U16V0MX-GP
NOPOP
1 2
R390
0R2J-2-GP
1 2
C364
SC47U16V0MX-GP
NOPOP
1 2
R384 0R2J-2-GP1 2
C361
SC47U16V0MX-GP
NOPOP
1 2
R483
2KR3F-L-GP
1 2
H3
HOLE
1
C358 
SC220P50V3JN-GP 
NOPOP 
1 2
R391
0R2J-2-GP
1 2
R388 0R2J-2-GP1 2
C357 
SC220P50V3JN-GP 
NOPOP 
1 2
C349
SC10U25V5KX-GP
1 2
TC3 
ST68U16VDM-1-GP 
1 2
R387 0R2J-2-GP1 2
TC4 
ST68U16VDM-1-GP 
1 2
H2
HOLE
1
C362
SC47U16V0MX-GP
NOPOP
1 2
C359 
SC220P50V3JN-GP 
NOPOP 
1 2
02 Do not mirror 
TOP BOTTOM 
GF1
GF-36P-24P-GP
P18 P18P17 P17
P16 P16P15 P15P14 P14P13 P13
P12 P12P11 P11P10 P10P9 P9
P8 P8P7 P7P6 P6P5 P5
P4 P4P3 P3P2 P2P1 P1
P25P25 P26P26 P27P27 P28P28
P29P29
P19P19 P20P20
P21P21 P22P22 P23P23 P24P24
S1 S1
S2 S2
S3 S3
S4 S4
S5 S5
S6 S6
S7 S7
S8 S8
S9 S9
S10 S10
S11 S11
S12 S12
S24S24
S23S23
S22S22
S21S21
S20S20
S19S19
S18S18
S17S17
S16S16
S15S15
S14S14
S13S13
P32P32
P31P31
P30P30
P36P36
P35P35
P34P34
P33P33
C360 
SC220P50V3JN-GP 
NOPOP 
1 2
SW1
SW-PUSH-3P-3-GP
1
2
3
4
5
CN4
FCI-CONN52-4R-GP
P1_1
P1_2 P1_3
P1_5
P1_6 P1_7
P1_8
P2_1
P2_2 P2_3
P2_4
P2_5
P2_6 P2_7
P2_8
NP1
NP2
P3_2
P3_1
P3_5
P3_6
P3_3
P3_4
P3_8
P3_7
P4_2
P4_1
P4_5
P4_6
P4_3
P4_4
P4_8
P4_7
A1
B1 C1
D1
A2
B2 C2
D2
P1_4
A3
A4
A5
B3
B4
B5
C3
C4
C5
D3
D4
D5
R386 0R2J-2-GP1 2
H1
HOLE
1
R385 0R2J-2-GP1 2
H4
HOLE
1
C355 
SC10U25V5KX-GP 
1 2



5
5
4
4
3
3
2
2
1
1
D D
C C
B B
A A
BLANK 
Title 
Size Document Number R e v 
Date: Sheet 
o f 
HONEY BADGER_PTB
-1
BLANK
A3
5 5Tuesday, January 20, 2015
Wiwynn
H/W R&D Dept. II
8F,90,Sec. 1,Hsin Tai Wu Rd,
Hsichih, Taipei Hsien 221, Taiwan, R.O.C
Title 
Size Document Number R e v 
Date: Sheet 
o f 
HONEY BADGER_PTB
-1
BLANK
A3
5 5Tuesday, January 20, 2015
Wiwynn
H/W R&D Dept. II
8F,90,Sec. 1,Hsin Tai Wu Rd,
Hsichih, Taipei Hsien 221, Taiwan, R.O.C
Title 
Size Document Number R e v 
Date: Sheet 
o f 
HONEY BADGER_PTB
-1
BLANK
A3
5 5Tuesday, January 20, 2015
Wiwynn
H/W R&D Dept. II
8F,90,Sec. 1,Hsin Tai Wu Rd,
Hsichih, Taipei Hsien 221, Taiwan, R.O.C